(kicad_pcb
	(version 20260206)
	(generator "pcbnew")
	(generator_version "10.0")
	(general
		(thickness 1.6)
		(legacy_teardrops no)
	)
	(paper "A4")
	(title_block
		(title "baseboard — 13948-1b.1110WZS1818.brd")
		(comment 1 "Honey Badger (Wiwynn) / footprints 190-196 of 2523")
	)
	(layers
		(0 "F.Cu" signal "TOP")
		(4 "In1.Cu" signal "L2GND")
		(6 "In2.Cu" signal "L3")
		(8 "In3.Cu" signal "L4VCC")
		(10 "In4.Cu" signal "L5VCC")
		(12 "In5.Cu" signal "L6")
		(14 "In6.Cu" signal "L7GND")
		(2 "B.Cu" signal "BOTTOM")
		(9 "F.Adhes" user "F.Adhesive")
		(11 "B.Adhes" user "B.Adhesive")
		(13 "F.Paste" user "Package Geometry/Pastemask Top")
		(15 "B.Paste" user "Package Geometry/Pastemask Bottom")
		(5 "F.SilkS" user "Ref Des/Silkscreen Top")
		(7 "B.SilkS" user "Ref Des/Silkscreen Bottom")
		(1 "F.Mask" user "Board Geometry/Soldermask Top")
		(3 "B.Mask" user "Board Geometry/Soldermask Bottom")
		(17 "Dwgs.User" user "User.Drawings")
		(19 "Cmts.User" user "User.Comments")
		(21 "Eco1.User" user "User.Eco1")
		(23 "Eco2.User" user "User.Eco2")
		(25 "Edge.Cuts" user "Board Geometry/Outline")
		(27 "Margin" user)
		(31 "F.CrtYd" user "Package Geometry/Place Bound Top")
		(29 "B.CrtYd" user "Package Geometry/Place Bound Bottom")
		(35 "F.Fab" user "Ref Des/Assembly Top")
		(33 "B.Fab" user "Ref Des/Assembly Bottom")
	)
	(footprint ""
		(layer "F.Cu")
		(at 214.00897 -69.088)
		(property "Reference" "R14"
			(at 0 0 0)
			(layer "F.SilkS")
			(hide yes)
			(effects
				(font
					(size 1.27 1.27)
				)
			)
		)
		(property "Value" "10KR2F-2-GP"
			(at 0.064008 -3.993896 0)
			(unlocked yes)
			(layer "F.Fab")
			(hide yes)
			(effects
				(font
					(size 1.016 1.016)
					(thickness 0.1524)
				)
			)
		)
		(property "Device Type" "R402H16"
			(at 0.064008 -5.517896 0)
			(unlocked yes)
			(layer "F.Fab")
			(hide yes)
			(effects
				(font
					(size 1.016 1.016)
					(thickness 0.1524)
				)
			)
		)
		(duplicate_pad_numbers_are_jumpers no)
		(fp_line
			(start -0.508 -0.9398)
			(end -0.508 0.9398)
			(stroke
				(width 0.1524)
				(type default)
			)
			(layer "F.SilkS")
		)
		(fp_line
			(start 0.508 -0.9398)
			(end -0.508 -0.9398)
			(stroke
				(width 0.1524)
				(type default)
			)
			(layer "F.SilkS")
		)
		(fp_rect
			(start -0.508 0.9398)
			(end 0.508 -0.9398)
			(stroke
				(width 0)
				(type default)
			)
			(fill no)
			(layer "F.CrtYd")
		)
		(fp_rect
			(start -0.508 0.9398)
			(end 0.508 -0.9398)
			(stroke
				(width 0)
				(type default)
			)
			(fill no)
			(layer "F.Fab")
		)
		(pad "1" smd custom
			(at 0 -0.4445)
			(size 0.1397 0.1397)
			(layers "F.Cu" "F.Mask" "F.Paste")
			(net "SVR_ID3")
			(options
				(clearance outline)
				(anchor circle)
			)
			(primitives
				(gr_poly
					(pts
						(arc
							(start -0.1778 -0.2794)
							(mid -0.249642 -0.249642)
							(end -0.2794 -0.1778)
						)
						(arc
							(start -0.2794 0.1778)
							(mid -0.249642 0.249642)
							(end -0.1778 0.2794)
						)
						(arc
							(start 0.1778 0.2794)
							(mid 0.249642 0.249642)
							(end 0.2794 0.1778)
						)
						(arc
							(start 0.2794 -0.1778)
							(mid 0.249642 -0.249642)
							(end 0.1778 -0.2794)
						)
					)
					(width 0)
					(fill yes)
				)
			)
		)
		(pad "2" smd custom
			(at 0 0.4445)
			(size 0.1397 0.1397)
			(layers "F.Cu" "F.Mask" "F.Paste")
			(net "P3V3_STBY")
			(options
				(clearance outline)
				(anchor circle)
			)
			(primitives
				(gr_poly
					(pts
						(arc
							(start -0.1778 -0.2794)
							(mid -0.249642 -0.249642)
							(end -0.2794 -0.1778)
						)
						(arc
							(start -0.2794 0.1778)
							(mid -0.249642 0.249642)
							(end -0.1778 0.2794)
						)
						(arc
							(start 0.1778 0.2794)
							(mid 0.249642 0.249642)
							(end 0.2794 0.1778)
						)
						(arc
							(start 0.2794 -0.1778)
							(mid 0.249642 -0.249642)
							(end 0.1778 -0.2794)
						)
					)
					(width 0)
					(fill yes)
				)
			)
		)
	)
	(footprint ""
		(layer "F.Cu")
		(at 279.781 -115.824 180)
		(property "Reference" "PR173"
			(at 0 0 180)
			(layer "F.SilkS")
			(hide yes)
			(effects
				(font
					(size 1.27 1.27)
				)
			)
		)
		(property "Value" "4K02R2F-GP"
			(at 0.064008 -3.993896 180)
			(unlocked yes)
			(layer "F.Fab")
			(hide yes)
			(effects
				(font
					(size 1.016 1.016)
					(thickness 0.1524)
				)
			)
		)
		(property "Device Type" "R402H16"
			(at 0.064008 -5.517896 180)
			(unlocked yes)
			(layer "F.Fab")
			(hide yes)
			(effects
				(font
					(size 1.016 1.016)
					(thickness 0.1524)
				)
			)
		)
		(duplicate_pad_numbers_are_jumpers no)
		(fp_line
			(start 0.508 -0.9398)
			(end -0.508 -0.9398)
			(stroke
				(width 0.1524)
				(type default)
			)
			(layer "F.SilkS")
		)
		(fp_line
			(start -0.508 -0.9398)
			(end -0.508 0.9398)
			(stroke
				(width 0.1524)
				(type default)
			)
			(layer "F.SilkS")
		)
		(fp_rect
			(start -0.508 0.9398)
			(end 0.508 -0.9398)
			(stroke
				(width 0)
				(type default)
			)
			(fill no)
			(layer "F.CrtYd")
		)
		(fp_rect
			(start -0.508 0.9398)
			(end 0.508 -0.9398)
			(stroke
				(width 0)
				(type default)
			)
			(fill no)
			(layer "F.Fab")
		)
		(pad "1" smd custom
			(at 0 -0.4445 180)
			(size 0.1397 0.1397)
			(layers "F.Cu" "F.Mask" "F.Paste")
			(net "P1V8_C_EN_G")
			(options
				(clearance outline)
				(anchor circle)
			)
			(primitives
				(gr_poly
					(pts
						(arc
							(start -0.1778 -0.2794)
							(mid -0.249642 -0.249642)
							(end -0.2794 -0.1778)
						)
						(arc
							(start -0.2794 0.1778)
							(mid -0.249642 0.249642)
							(end -0.1778 0.2794)
						)
						(arc
							(start 0.1778 0.2794)
							(mid 0.249642 0.249642)
							(end 0.2794 0.1778)
						)
						(arc
							(start 0.2794 -0.1778)
							(mid 0.249642 -0.249642)
							(end 0.1778 -0.2794)
						)
					)
					(width 0)
					(fill yes)
				)
			)
		)
		(pad "2" smd custom
			(at 0 0.4445 180)
			(size 0.1397 0.1397)
			(layers "F.Cu" "F.Mask" "F.Paste")
			(net "P3V3_STBY")
			(options
				(clearance outline)
				(anchor circle)
			)
			(primitives
				(gr_poly
					(pts
						(arc
							(start -0.1778 -0.2794)
							(mid -0.249642 -0.249642)
							(end -0.2794 -0.1778)
						)
						(arc
							(start -0.2794 0.1778)
							(mid -0.249642 0.249642)
							(end -0.1778 0.2794)
						)
						(arc
							(start 0.1778 0.2794)
							(mid 0.249642 0.249642)
							(end 0.2794 0.1778)
						)
						(arc
							(start 0.2794 -0.1778)
							(mid 0.249642 -0.249642)
							(end 0.1778 -0.2794)
						)
					)
					(width 0)
					(fill yes)
				)
			)
		)
	)
	(footprint ""
		(layer "F.Cu")
		(at 57.658 -224.409 90)
		(property "Reference" "C372"
			(at 0 0 90)
			(layer "F.SilkS")
			(hide yes)
			(effects
				(font
					(size 1.27 1.27)
				)
			)
		)
		(property "Value" "SCD015U25V2KX-GP"
			(at 1.1811 -2.7051 90)
			(unlocked yes)
			(layer "F.Fab")
			(hide yes)
			(effects
				(font
					(size 1.016 1.016)
					(thickness 0.1524)
				)
			)
		)
		(property "Device Type" "C402H22"
			(at 1.1811 -4.2291 90)
			(unlocked yes)
			(layer "F.Fab")
			(hide yes)
			(effects
				(font
					(size 1.016 1.016)
					(thickness 0.1524)
				)
			)
		)
		(duplicate_pad_numbers_are_jumpers no)
		(fp_rect
			(start -0.4318 0.9525)
			(end 0.4318 -0.9525)
			(stroke
				(width 0)
				(type default)
			)
			(fill no)
			(layer "F.CrtYd")
		)
		(fp_rect
			(start -0.4318 0.9525)
			(end 0.4318 -0.9525)
			(stroke
				(width 0)
				(type default)
			)
			(fill no)
			(layer "F.Fab")
		)
		(pad "1" smd custom
			(at 0 -0.4445 90)
			(size 0.1524 0.1524)
			(layers "F.Cu" "F.Mask" "F.Paste")
			(net "MB0_CM_SENSE_P")
			(options
				(clearance outline)
				(anchor circle)
			)
			(primitives
				(gr_poly
					(pts
						(arc
							(start 0.3048 -0.2032)
							(mid 0.275042 -0.275042)
							(end 0.2032 -0.3048)
						)
						(arc
							(start -0.2032 -0.3048)
							(mid -0.275042 -0.275042)
							(end -0.3048 -0.2032)
						)
						(arc
							(start -0.3048 0.2032)
							(mid -0.275042 0.275042)
							(end -0.2032 0.3048)
						)
						(arc
							(start 0.2032 0.3048)
							(mid 0.275042 0.275042)
							(end 0.3048 0.2032)
						)
					)
					(width 0)
					(fill yes)
				)
			)
		)
		(pad "2" smd custom
			(at 0 0.4445 90)
			(size 0.1524 0.1524)
			(layers "F.Cu" "F.Mask" "F.Paste")
			(net "MB0_CM_SENSE_N")
			(options
				(clearance outline)
				(anchor circle)
			)
			(primitives
				(gr_poly
					(pts
						(arc
							(start 0.3048 -0.2032)
							(mid 0.275042 -0.275042)
							(end 0.2032 -0.3048)
						)
						(arc
							(start -0.2032 -0.3048)
							(mid -0.275042 -0.275042)
							(end -0.3048 -0.2032)
						)
						(arc
							(start -0.3048 0.2032)
							(mid -0.275042 0.275042)
							(end -0.2032 0.3048)
						)
						(arc
							(start 0.2032 0.3048)
							(mid 0.275042 0.275042)
							(end 0.3048 0.2032)
						)
					)
					(width 0)
					(fill yes)
				)
			)
		)
	)
	(footprint ""
		(layer "F.Cu")
		(at 334.899 -113.538 180)
		(property "Reference" "PR22"
			(at 0 0 180)
			(layer "F.SilkS")
			(hide yes)
			(effects
				(font
					(size 1.27 1.27)
				)
			)
		)
		(property "Value" "0R2J-2-GP"
			(at 0.064008 -3.993896 180)
			(unlocked yes)
			(layer "F.Fab")
			(hide yes)
			(effects
				(font
					(size 1.016 1.016)
					(thickness 0.1524)
				)
			)
		)
		(property "Device Type" "R402H16"
			(at 0.064008 -5.517896 180)
			(unlocked yes)
			(layer "F.Fab")
			(hide yes)
			(effects
				(font
					(size 1.016 1.016)
					(thickness 0.1524)
				)
			)
		)
		(duplicate_pad_numbers_are_jumpers no)
		(fp_line
			(start 0.508 -0.9398)
			(end -0.508 -0.9398)
			(stroke
				(width 0.1524)
				(type default)
			)
			(layer "F.SilkS")
		)
		(fp_line
			(start -0.508 -0.9398)
			(end -0.508 0.9398)
			(stroke
				(width 0.1524)
				(type default)
			)
			(layer "F.SilkS")
		)
		(fp_rect
			(start -0.508 0.9398)
			(end 0.508 -0.9398)
			(stroke
				(width 0)
				(type default)
			)
			(fill no)
			(layer "F.CrtYd")
		)
		(fp_rect
			(start -0.508 0.9398)
			(end 0.508 -0.9398)
			(stroke
				(width 0)
				(type default)
			)
			(fill no)
			(layer "F.Fab")
		)
		(pad "1" smd custom
			(at 0 -0.4445 180)
			(size 0.1397 0.1397)
			(layers "F.Cu" "F.Mask" "F.Paste")
			(net "P5V_STBY_EN_R")
			(options
				(clearance outline)
				(anchor circle)
			)
			(primitives
				(gr_poly
					(pts
						(arc
							(start -0.1778 -0.2794)
							(mid -0.249642 -0.249642)
							(end -0.2794 -0.1778)
						)
						(arc
							(start -0.2794 0.1778)
							(mid -0.249642 0.249642)
							(end -0.1778 0.2794)
						)
						(arc
							(start 0.1778 0.2794)
							(mid 0.249642 0.249642)
							(end 0.2794 0.1778)
						)
						(arc
							(start 0.2794 -0.1778)
							(mid 0.249642 -0.249642)
							(end 0.1778 -0.2794)
						)
					)
					(width 0)
					(fill yes)
				)
			)
		)
		(pad "2" smd custom
			(at 0 0.4445 180)
			(size 0.1397 0.1397)
			(layers "F.Cu" "F.Mask" "F.Paste")
			(net "MB0_P12V_PWRGOOD")
			(options
				(clearance outline)
				(anchor circle)
			)
			(primitives
				(gr_poly
					(pts
						(arc
							(start -0.1778 -0.2794)
							(mid -0.249642 -0.249642)
							(end -0.2794 -0.1778)
						)
						(arc
							(start -0.2794 0.1778)
							(mid -0.249642 0.249642)
							(end -0.1778 0.2794)
						)
						(arc
							(start 0.1778 0.2794)
							(mid 0.249642 0.249642)
							(end 0.2794 0.1778)
						)
						(arc
							(start 0.2794 -0.1778)
							(mid 0.249642 -0.249642)
							(end 0.1778 -0.2794)
						)
					)
					(width 0)
					(fill yes)
				)
			)
		)
	)
	(footprint ""
		(layer "F.Cu")
		(at 147.193 -92.456 180)
		(property "Reference" "SC1182"
			(at 0 0 180)
			(layer "F.SilkS")
			(hide yes)
			(effects
				(font
					(size 1.27 1.27)
				)
			)
		)
		(property "Value" "SC100U6D3V0MX-2GP"
			(at -0.00254 -4.78536 180)
			(unlocked yes)
			(layer "F.Fab")
			(hide yes)
			(effects
				(font
					(size 1.016 1.016)
					(thickness 0.1524)
				)
			)
		)
		(property "Device Type" "C1210H107"
			(at -0.00254 -6.38048 180)
			(unlocked yes)
			(layer "F.Fab")
			(hide yes)
			(effects
				(font
					(size 1.016 1.016)
					(thickness 0.1524)
				)
			)
		)
		(duplicate_pad_numbers_are_jumpers no)
		(fp_line
			(start 1.5748 2.3368)
			(end 1.5748 0.762)
			(stroke
				(width 0.1524)
				(type default)
			)
			(layer "F.SilkS")
		)
		(fp_line
			(start 1.5748 -0.762)
			(end 1.5748 -2.3368)
			(stroke
				(width 0.1524)
				(type default)
			)
			(layer "F.SilkS")
		)
		(fp_line
			(start 1.5748 -2.3368)
			(end -1.5748 -2.3368)
			(stroke
				(width 0.1524)
				(type default)
			)
			(layer "F.SilkS")
		)
		(fp_line
			(start -1.5748 2.3368)
			(end 1.5748 2.3368)
			(stroke
				(width 0.1524)
				(type default)
			)
			(layer "F.SilkS")
		)
		(fp_line
			(start -1.5748 0.762)
			(end -1.5748 2.3368)
			(stroke
				(width 0.1524)
				(type default)
			)
			(layer "F.SilkS")
		)
		(fp_line
			(start -1.5748 -2.3368)
			(end -1.5748 -0.762)
			(stroke
				(width 0.1524)
				(type default)
			)
			(layer "F.SilkS")
		)
		(fp_rect
			(start -1.651 2.413)
			(end 1.651 -2.413)
			(stroke
				(width 0)
				(type default)
			)
			(fill no)
			(layer "F.CrtYd")
		)
		(fp_poly
			(pts
				(xy 1.651 2.413) (xy 1.651 -2.413) (xy -1.651 -2.413) (xy -1.651 2.413)
			)
			(stroke
				(width 0)
				(type default)
			)
			(fill no)
			(layer "F.Fab")
		)
		(pad "1" smd rect
			(at 0 -1.4732 180)
			(size 2.794 1.397)
			(layers "F.Cu" "F.Mask" "F.Paste")
			(net "GND")
		)
		(pad "2" smd rect
			(at 0 1.4732 180)
			(size 2.794 1.397)
			(layers "F.Cu" "F.Mask" "F.Paste")
			(net "GB_VDDA")
		)
	)
	(footprint ""
		(layer "F.Cu")
		(at 113.792 -27.94 -90)
		(property "Reference" "SR662"
			(at 0 0 270)
			(layer "F.SilkS")
			(hide yes)
			(effects
				(font
					(size 1.27 1.27)
				)
			)
		)
		(property "Value" "10KR2F-2-GP"
			(at 0.064008 -3.993896 270)
			(unlocked yes)
			(layer "F.Fab")
			(hide yes)
			(effects
				(font
					(size 1.016 1.016)
					(thickness 0.1524)
				)
			)
		)
		(property "Device Type" "R402H16"
			(at 0.064008 -5.517896 270)
			(unlocked yes)
			(layer "F.Fab")
			(hide yes)
			(effects
				(font
					(size 1.016 1.016)
					(thickness 0.1524)
				)
			)
		)
		(duplicate_pad_numbers_are_jumpers no)
		(fp_line
			(start -0.508 -0.9398)
			(end -0.508 0.9398)
			(stroke
				(width 0.1524)
				(type default)
			)
			(layer "F.SilkS")
		)
		(fp_line
			(start 0.508 -0.9398)
			(end -0.508 -0.9398)
			(stroke
				(width 0.1524)
				(type default)
			)
			(layer "F.SilkS")
		)
		(fp_rect
			(start -0.508 0.9398)
			(end 0.508 -0.9398)
			(stroke
				(width 0)
				(type default)
			)
			(fill no)
			(layer "F.CrtYd")
		)
		(fp_rect
			(start -0.508 0.9398)
			(end 0.508 -0.9398)
			(stroke
				(width 0)
				(type default)
			)
			(fill no)
			(layer "F.Fab")
		)
		(pad "1" smd custom
			(at 0 -0.4445 270)
			(size 0.1397 0.1397)
			(layers "F.Cu" "F.Mask" "F.Paste")
			(net "P1V8_C")
			(options
				(clearance outline)
				(anchor circle)
			)
			(primitives
				(gr_poly
					(pts
						(arc
							(start -0.1778 -0.2794)
							(mid -0.249642 -0.249642)
							(end -0.2794 -0.1778)
						)
						(arc
							(start -0.2794 0.1778)
							(mid -0.249642 0.249642)
							(end -0.1778 0.2794)
						)
						(arc
							(start 0.1778 0.2794)
							(mid 0.249642 0.249642)
							(end 0.2794 0.1778)
						)
						(arc
							(start 0.2794 -0.1778)
							(mid 0.249642 -0.249642)
							(end 0.1778 -0.2794)
						)
					)
					(width 0)
					(fill yes)
				)
			)
		)
		(pad "2" smd custom
			(at 0 0.4445 270)
			(size 0.1397 0.1397)
			(layers "F.Cu" "F.Mask" "F.Paste")
			(net "SYS_DBMODE3")
			(options
				(clearance outline)
				(anchor circle)
			)
			(primitives
				(gr_poly
					(pts
						(arc
							(start -0.1778 -0.2794)
							(mid -0.249642 -0.249642)
							(end -0.2794 -0.1778)
						)
						(arc
							(start -0.2794 0.1778)
							(mid -0.249642 0.249642)
							(end -0.1778 0.2794)
						)
						(arc
							(start 0.1778 0.2794)
							(mid 0.249642 0.249642)
							(end 0.2794 0.1778)
						)
						(arc
							(start 0.2794 -0.1778)
							(mid 0.249642 -0.249642)
							(end 0.1778 -0.2794)
						)
					)
					(width 0)
					(fill yes)
				)
			)
		)
	)
	(footprint ""
		(layer "F.Cu")
		(at 305.816 -190.246 90)
		(property "Reference" "R226"
			(at 0 0 90)
			(layer "F.SilkS")
			(hide yes)
			(effects
				(font
					(size 1.27 1.27)
				)
			)
		)
		(property "Value" "10KR2F-2-GP"
			(at 0.064008 -3.993896 90)
			(unlocked yes)
			(layer "F.Fab")
			(hide yes)
			(effects
				(font
					(size 1.016 1.016)
					(thickness 0.1524)
				)
			)
		)
		(property "Device Type" "R402H16"
			(at 0.064008 -5.517896 90)
			(unlocked yes)
			(layer "F.Fab")
			(hide yes)
			(effects
				(font
					(size 1.016 1.016)
					(thickness 0.1524)
				)
			)
		)
		(duplicate_pad_numbers_are_jumpers no)
		(fp_line
			(start 0.508 -0.9398)
			(end -0.508 -0.9398)
			(stroke
				(width 0.1524)
				(type default)
			)
			(layer "F.SilkS")
		)
		(fp_line
			(start -0.508 -0.9398)
			(end -0.508 0.9398)
			(stroke
				(width 0.1524)
				(type default)
			)
			(layer "F.SilkS")
		)
		(fp_rect
			(start -0.508 0.9398)
			(end 0.508 -0.9398)
			(stroke
				(width 0)
				(type default)
			)
			(fill no)
			(layer "F.CrtYd")
		)
		(fp_rect
			(start -0.508 0.9398)
			(end 0.508 -0.9398)
			(stroke
				(width 0)
				(type default)
			)
			(fill no)
			(layer "F.Fab")
		)
		(pad "1" smd custom
			(at 0 -0.4445 90)
			(size 0.1397 0.1397)
			(layers "F.Cu" "F.Mask" "F.Paste")
			(net "P3V3_STBY")
			(options
				(clearance outline)
				(anchor circle)
			)
			(primitives
				(gr_poly
					(pts
						(arc
							(start -0.1778 -0.2794)
							(mid -0.249642 -0.249642)
							(end -0.2794 -0.1778)
						)
						(arc
							(start -0.2794 0.1778)
							(mid -0.249642 0.249642)
							(end -0.1778 0.2794)
						)
						(arc
							(start 0.1778 0.2794)
							(mid 0.249642 0.249642)
							(end 0.2794 0.1778)
						)
						(arc
							(start 0.2794 -0.1778)
							(mid 0.249642 -0.249642)
							(end 0.1778 -0.2794)
						)
					)
					(width 0)
					(fill yes)
				)
			)
		)
		(pad "2" smd custom
			(at 0 0.4445 90)
			(size 0.1397 0.1397)
			(layers "F.Cu" "F.Mask" "F.Paste")
			(net "CONN_10G_PRSNT2_N")
			(options
				(clearance outline)
				(anchor circle)
			)
			(primitives
				(gr_poly
					(pts
						(arc
							(start -0.1778 -0.2794)
							(mid -0.249642 -0.249642)
							(end -0.2794 -0.1778)
						)
						(arc
							(start -0.2794 0.1778)
							(mid -0.249642 0.249642)
							(end -0.1778 0.2794)
						)
						(arc
							(start 0.1778 0.2794)
							(mid 0.249642 0.249642)
							(end 0.2794 0.1778)
						)
						(arc
							(start 0.2794 -0.1778)
							(mid 0.249642 -0.249642)
							(end 0.1778 -0.2794)
						)
					)
					(width 0)
					(fill yes)
				)
			)
		)
	)
)
